# T6G (Grand Teton) — schematic netlist excerpt (pin names and nets, part order shuffled) for the footprints in the layout excerpt that follows; sources: Cadence DE-HDL packaged netlist, KiCad conversion of 04192023_DAF0TMB3IC0_F0TG_MB_C_brd_V02_OCP.brd

R6328  Q_RES  0 5% CHIP  pkg 0402LF  page 178 : A = RST_USB_HUB_N ; B = USB_HUB2_TI_GRSTZ_MRP_PROG_FUNC1
C712  Q_CAP_DIFFBUS  DIFF BUS_0.22UF 6.3V 20% X6S  pkg C0201  page 66 : \1\ = P5E_CPU1_P1_TX_C_DN<14> ; \2\ = P5E_CPU1_P1_TX_DN<14>
C879  Q_CAP_DIFFBUS  DIFF BUS_0.22UF 6.3V 20% X6S  pkg C0201  page 64 : \1\ = P5E_CPU0_P3_TX_C_DP<11> ; \2\ = P5E_CPU0_P3_TX_DP<11>
C41  Q_CAP_DIFFBUS  DIFF BUS_0.22UF 6.3V 20% X6S  pkg C0201  page 65 : \1\ = P5E_CPU0_G3_TX_C_DN<12> ; \2\ = P5E_CPU0_G3_TX_DN<12>

(kicad_pcb
	(version 20260206)
	(generator "pcbnew")
	(generator_version "10.0")
	(general
		(thickness 1.6)
		(legacy_teardrops no)
	)
	(paper "A4")
	(title_block
		(title "04192023_DAF0TMB3IC0_F0TG_MB_C_brd_V02_OCP.brd")
		(comment 1 "Grand Teton / footprints 4265-4268 of 8354")
	)
	(layers
		(0 "F.Cu" signal "TOP")
		(4 "In1.Cu" signal "GND")
		(6 "In2.Cu" signal "IN1")
		(8 "In3.Cu" signal "GND1")
		(10 "In4.Cu" signal "IN2")
		(12 "In5.Cu" signal "GND2")
		(14 "In6.Cu" signal "IN3")
		(16 "In7.Cu" signal "GND3")
		(18 "In8.Cu" signal "VCC")
		(20 "In9.Cu" signal "VCC1")
		(22 "In10.Cu" signal "GND4")
		(24 "In11.Cu" signal "IN4")
		(26 "In12.Cu" signal "GND5")
		(28 "In13.Cu" signal "IN5")
		(30 "In14.Cu" signal "GND6")
		(32 "In15.Cu" signal "IN6")
		(34 "In16.Cu" signal "GND7")
		(2 "B.Cu" signal "BOTTOM")
		(9 "F.Adhes" user "F.Adhesive")
		(11 "B.Adhes" user "B.Adhesive")
		(13 "F.Paste" user "Package Geometry/Pastemask Top")
		(15 "B.Paste" user "Package Geometry/Pastemask Bottom")
		(5 "F.SilkS" user "Ref Des/Silkscreen Top")
		(7 "B.SilkS" user "Ref Des/Silkscreen Bottom")
		(1 "F.Mask" user "Board Geometry/Soldermask Top")
		(3 "B.Mask" user "Board Geometry/Soldermask Bottom")
		(17 "Dwgs.User" user "User.Drawings")
		(19 "Cmts.User" user "User.Comments")
		(21 "Eco1.User" user "User.Eco1")
		(23 "Eco2.User" user "User.Eco2")
		(25 "Edge.Cuts" user "Board Geometry/Outline")
		(27 "Margin" user)
		(31 "F.CrtYd" user "Package Geometry/Place Bound Top")
		(29 "B.CrtYd" user "Package Geometry/Place Bound Bottom")
		(35 "F.Fab" user "Ref Des/Assembly Top")
		(33 "B.Fab" user "Ref Des/Assembly Bottom")
	)
	(footprint ""
		(layer "F.Cu")
		(at 386.511292 -381.41783 -90)
		(property "Reference" "C879"
			(at 0 0 270)
			(layer "F.SilkS")
			(hide yes)
			(effects
				(font
					(size 1.27 1.27)
				)
			)
		)
		(property "Value" ""
			(at 0 0 270)
			(layer "F.Fab")
			(effects
				(font
					(size 1.27 1.27)
				)
			)
		)
		(duplicate_pad_numbers_are_jumpers no)
		(fp_line
			(start -0.299974 0.150114)
			(end -0.299974 -0.150114)
			(stroke
				(width 0.1)
				(type default)
			)
			(layer "F.Fab")
		)
		(fp_line
			(start 0.299974 0.150114)
			(end -0.299974 0.150114)
			(stroke
				(width 0.1)
				(type default)
			)
			(layer "F.Fab")
		)
		(fp_line
			(start -0.299974 -0.150114)
			(end 0.299974 -0.150114)
			(stroke
				(width 0.1)
				(type default)
			)
			(layer "F.Fab")
		)
		(fp_line
			(start 0.299974 -0.150114)
			(end 0.299974 0.150114)
			(stroke
				(width 0.1)
				(type default)
			)
			(layer "F.Fab")
		)
		(pad "1" smd rect
			(at -0.2667 0 270)
			(size 0.3048 0.381)
			(layers "F.Cu" "F.Mask" "F.Paste")
			(net "P5E_CPU0_P3_TX_C_DP<11>")
		)
		(pad "2" smd rect
			(at 0.2667 0 270)
			(size 0.3048 0.381)
			(layers "F.Cu" "F.Mask" "F.Paste")
			(net "P5E_CPU0_P3_TX_DP<11>")
		)
	)
	(footprint ""
		(layer "F.Cu")
		(at 101.413056 -31.786576 90)
		(property "Reference" "R6328"
			(at 0 0 90)
			(layer "F.SilkS")
			(hide yes)
			(effects
				(font
					(size 1.27 1.27)
				)
			)
		)
		(property "Value" ""
			(at 0 0 90)
			(layer "F.Fab")
			(effects
				(font
					(size 1.27 1.27)
				)
			)
		)
		(duplicate_pad_numbers_are_jumpers no)
		(fp_line
			(start 0.7874 -0.4064)
			(end 0.7874 0.4064)
			(stroke
				(width 0.1524)
				(type default)
			)
			(layer "F.SilkS")
		)
		(fp_line
			(start -0.7874 -0.4064)
			(end 0.7874 -0.4064)
			(stroke
				(width 0.1524)
				(type default)
			)
			(layer "F.SilkS")
		)
		(fp_line
			(start 0.7874 0.4064)
			(end -0.7874 0.4064)
			(stroke
				(width 0.1524)
				(type default)
			)
			(layer "F.SilkS")
		)
		(fp_line
			(start -0.7874 0.4064)
			(end -0.7874 -0.4064)
			(stroke
				(width 0.1524)
				(type default)
			)
			(layer "F.SilkS")
		)
		(fp_line
			(start -0.12065 -0.305054)
			(end -0.12065 -0.2794)
			(stroke
				(width 0.1)
				(type default)
			)
			(layer "F.Fab")
		)
		(fp_line
			(start -0.67945 -0.305054)
			(end -0.12065 -0.305054)
			(stroke
				(width 0.1)
				(type default)
			)
			(layer "F.Fab")
		)
		(fp_line
			(start 0.67945 -0.3048)
			(end 0.67945 0.3048)
			(stroke
				(width 0.1)
				(type default)
			)
			(layer "F.Fab")
		)
		(fp_line
			(start 0.12065 -0.3048)
			(end 0.67945 -0.3048)
			(stroke
				(width 0.1)
				(type default)
			)
			(layer "F.Fab")
		)
		(fp_line
			(start 0.12065 -0.2794)
			(end 0.12065 -0.3048)
			(stroke
				(width 0.1)
				(type default)
			)
			(layer "F.Fab")
		)
		(fp_line
			(start -0.12065 -0.2794)
			(end 0.12065 -0.2794)
			(stroke
				(width 0.1)
				(type default)
			)
			(layer "F.Fab")
		)
		(fp_line
			(start 0.120396 0.2794)
			(end -0.12065 0.2794)
			(stroke
				(width 0.1)
				(type default)
			)
			(layer "F.Fab")
		)
		(fp_line
			(start -0.12065 0.2794)
			(end -0.12065 0.3048)
			(stroke
				(width 0.1)
				(type default)
			)
			(layer "F.Fab")
		)
		(fp_line
			(start 0.67945 0.3048)
			(end 0.120396 0.3048)
			(stroke
				(width 0.1)
				(type default)
			)
			(layer "F.Fab")
		)
		(fp_line
			(start 0.120396 0.3048)
			(end 0.120396 0.2794)
			(stroke
				(width 0.1)
				(type default)
			)
			(layer "F.Fab")
		)
		(fp_line
			(start -0.12065 0.3048)
			(end -0.67945 0.3048)
			(stroke
				(width 0.1)
				(type default)
			)
			(layer "F.Fab")
		)
		(fp_line
			(start -0.67945 0.3048)
			(end -0.67945 -0.305054)
			(stroke
				(width 0.1)
				(type default)
			)
			(layer "F.Fab")
		)
		(pad "1" smd circle
			(at -0.40005 0 90)
			(size 0 0)
			(layers "F.Cu" "F.Mask" "F.Paste")
			(net "RST_USB_HUB_N")
		)
		(pad "2" smd circle
			(at 0.40005 0 90)
			(size 0 0)
			(layers "F.Cu" "F.Mask" "F.Paste")
			(net "USB_HUB2_TI_GRSTZ_MRP_PROG_FUNC1")
		)
	)
	(footprint ""
		(layer "F.Cu")
		(at 102.268782 -376.067828)
		(property "Reference" "C712"
			(at 0 0 0)
			(layer "F.SilkS")
			(hide yes)
			(effects
				(font
					(size 1.27 1.27)
				)
			)
		)
		(property "Value" ""
			(at 0 0 0)
			(layer "F.Fab")
			(effects
				(font
					(size 1.27 1.27)
				)
			)
		)
		(duplicate_pad_numbers_are_jumpers no)
		(fp_line
			(start -0.299974 -0.150114)
			(end 0.299974 -0.150114)
			(stroke
				(width 0.1)
				(type default)
			)
			(layer "F.Fab")
		)
		(fp_line
			(start -0.299974 0.150114)
			(end -0.299974 -0.150114)
			(stroke
				(width 0.1)
				(type default)
			)
			(layer "F.Fab")
		)
		(fp_line
			(start 0.299974 -0.150114)
			(end 0.299974 0.150114)
			(stroke
				(width 0.1)
				(type default)
			)
			(layer "F.Fab")
		)
		(fp_line
			(start 0.299974 0.150114)
			(end -0.299974 0.150114)
			(stroke
				(width 0.1)
				(type default)
			)
			(layer "F.Fab")
		)
		(pad "1" smd rect
			(at -0.2667 0)
			(size 0.3048 0.381)
			(layers "F.Cu" "F.Mask" "F.Paste")
			(net "P5E_CPU1_P1_TX_C_DN<14>")
		)
		(pad "2" smd rect
			(at 0.2667 0)
			(size 0.3048 0.381)
			(layers "F.Cu" "F.Mask" "F.Paste")
			(net "P5E_CPU1_P1_TX_DN<14>")
		)
	)
	(footprint ""
		(layer "F.Cu")
		(at 398.389348 -17.624298 90)
		(property "Reference" "C41"
			(at 0 0 90)
			(layer "F.SilkS")
			(hide yes)
			(effects
				(font
					(size 1.27 1.27)
				)
			)
		)
		(property "Value" ""
			(at 0 0 90)
			(layer "F.Fab")
			(effects
				(font
					(size 1.27 1.27)
				)
			)
		)
		(duplicate_pad_numbers_are_jumpers no)
		(fp_line
			(start 0.299974 -0.150114)
			(end 0.299974 0.150114)
			(stroke
				(width 0.1)
				(type default)
			)
			(layer "F.Fab")
		)
		(fp_line
			(start -0.299974 -0.150114)
			(end 0.299974 -0.150114)
			(stroke
				(width 0.1)
				(type default)
			)
			(layer "F.Fab")
		)
		(fp_line
			(start 0.299974 0.150114)
			(end -0.299974 0.150114)
			(stroke
				(width 0.1)
				(type default)
			)
			(layer "F.Fab")
		)
		(fp_line
			(start -0.299974 0.150114)
			(end -0.299974 -0.150114)
			(stroke
				(width 0.1)
				(type default)
			)
			(layer "F.Fab")
		)
		(pad "1" smd rect
			(at -0.2667 0 90)
			(size 0.3048 0.381)
			(layers "F.Cu" "F.Mask" "F.Paste")
			(net "P5E_CPU0_G3_TX_C_DN<12>")
		)
		(pad "2" smd rect
			(at 0.2667 0 90)
			(size 0.3048 0.381)
			(layers "F.Cu" "F.Mask" "F.Paste")
			(net "P5E_CPU0_G3_TX_DN<12>")
		)
	)
)
